# T6G (Grand Teton) — schematic parts with pin connectivity, parts 344–518 of 8303; source: Cadence DE-HDL packaged netlist (pstxprt.dat, pstxnet.dat, pstchip.dat)

C343  Q_CAP  4.7UF 6.3V 20% X6S  pkg 0402  page 334 : 1 = P0V9_CPU1_RT1_2A ; 2 = GND
C344  Q_CAP  0.1UF 10V 10% X7S  pkg C0201  page 334 : 1 = P0V9_CPU1_RT1_2A ; 2 = GND
C345  Q_CAP  0.1UF 25V 10% EMPTY  pkg 0402  page 269 : 1 = P1V8_AUX_ENABLE ; 2 = GND
C346  Q_CAP  1UF 4V 20% X6S  pkg 0201  page 334 : 1 = P0V9_CPU1_RT1_2A ; 2 = GND
C347  Q_CAP  0.1UF 25V 10% X7R  pkg 0402  page 259 : 1 = P1V8_AUX ; 2 = GND
C348  Q_CAP  0.1UF 25V 10% EMPTY  pkg 0402  page 192 : 1 = PVDD33_S5_EN ; 2 = GND
C349  Q_CAP  0.1UF 10V 10% X7S  pkg C0201  page 334 : 1 = P0V9_CPU1_RT1_2A ; 2 = GND
C350  Q_CAP  0.1UF 10V 10% X7S  pkg C0201  page 334 : 1 = P0V9_CPU1_RT1_2A ; 2 = GND
C351  Q_CAP  22UF 4V 20% X6S  pkg C0402  page 334 : 1 = P0V9_CPU1_RT1_2A ; 2 = GND
C352  Q_CAP  0.1UF 16V 10% X7R  pkg C0402  page 83 : 1 = P1V8_AUX ; 2 = GND
C353  Q_CAP  1UF 4V 20% X6S  pkg 0201  page 334 : 1 = P0V9_CPU1_RT1_2A ; 2 = GND
C354  Q_CAP  10UF 6.3V 20% X6S  pkg C0402  page 334 : 1 = P0V9_CPU1_RT1_2A ; 2 = GND
C355  Q_CAP  0.1UF 16V 10% X7R  pkg C0402  page 83 : 1 = P3V3_AUX ; 2 = GND
C356  Q_CAP  0.1UF 16V 10% X7R  pkg C0402  page 83 : 1 = P3V3_AUX ; 2 = GND
C357  Q_CAP  0.1UF 16V 10% X7R  pkg C0402  page 83 : 1 = P3V3_AUX ; 2 = GND
C358  Q_CAP  0.1UF 16V 10% X7R  pkg C0402  page 83 : 1 = P3V3_AUX ; 2 = GND
C359  Q_CAP  0.1UF 16V 10% X7R  pkg C0402  page 83 : 1 = P3V3_AUX ; 2 = GND
C360  Q_CAP  0.1UF 16V 10% X7R  pkg C0402  page 83 : 1 = P3V3_AUX ; 2 = GND
C361  Q_CAP  0.1UF 16V 10% X7R  pkg C0402  page 83 : 1 = P3V3_AUX ; 2 = GND
C362  Q_CAP  0.1UF 16V 10% X7R  pkg C0402  page 83 : 1 = P3V3_AUX ; 2 = GND
C363  Q_CAP  220PF 50V 5% C0G  pkg C0402  page 164 : 1 = UART_CPU0_LVC3_UART0_TX ; 2 = GND
C364  Q_CAP  220PF 50V 5% C0G  pkg C0402  page 164 : 1 = UART_CPU0_LVC3_UART0_RX ; 2 = GND
C365  Q_CAP  0.1UF 10V 10% X7S  pkg C0201  page 185 : 1 = P1V8_AUX ; 2 = GND
C366  Q_CAP  100UF 4V 20% X6S  pkg C0805  page 345 : 1 = P1V8_CPU1_RT_1D ; 2 = GND
C367  Q_CAP  100UF 4V 20% X6S  pkg C0805  page 345 : 1 = P1V8_CPU1_RT2_1A ; 2 = GND
C368  Q_CAP  22UF 4V 20% X6S  pkg C0402  page 345 : 1 = P1V8_CPU1_RT_1D ; 2 = GND
C369  Q_CAP  22UF 4V 20% X6S  pkg C0402  page 345 : 1 = P1V8_CPU1_RT2_1A ; 2 = GND
C370  Q_CAP  10UF 6.3V 20% X6S  pkg C0402  page 345 : 1 = P1V8_CPU1_RT_1D ; 2 = GND
C371  Q_CAP  4.7UF 6.3V 20% X6S  pkg 0402  page 345 : 1 = P1V8_CPU1_RT2_1A ; 2 = GND
C372  Q_CAP  10UF 6.3V 20% X6S  pkg C0402  page 345 : 1 = P1V8_CPU1_RT2_1A ; 2 = GND
C373  Q_CAP  4.7UF 6.3V 20% X6S  pkg 0402  page 345 : 1 = P1V8_CPU1_RT_1D ; 2 = GND
C374  Q_CAP  1UF 4V 20% X6S  pkg 0201  page 345 : 1 = P1V8_CPU1_RT2_1A ; 2 = GND
C375  Q_CAP  1UF 4V 20% X6S  pkg 0201  page 345 : 1 = P1V8_CPU1_RT2_1A_1D ; 2 = GND
C376  Q_CAP  1UF 4V 20% X6S  pkg 0201  page 345 : 1 = P1V8_CPU1_RT2_1A ; 2 = GND
C377  Q_CAP  0.1UF 10V 10% X7S  pkg C0201  page 345 : 1 = P1V8_CPU1_RT2_1A ; 2 = GND
C378  Q_CAP  0.1UF 10V 10% X7S  pkg C0201  page 345 : 1 = P1V8_CPU1_RT2_1A_1D ; 2 = GND
C379  Q_CAP  0.1UF 10V 10% X7S  pkg C0201  page 345 : 1 = P1V8_CPU1_RT2_1A ; 2 = GND
C380  Q_CAP  0.1UF 10V 10% X7S  pkg C0201  page 345 : 1 = P1V8_CPU1_RT2_1A ; 2 = GND
C381  Q_CAP  0.1UF 10V 10% X7S  pkg C0201  page 345 : 1 = P1V8_CPU1_RT2_1A ; 2 = GND
C382  Q_CAP  1UF 4V 20% X6S  pkg 0201  page 345 : 1 = P0V9_CPU1_RT2_2A ; 2 = GND
C383  Q_CAP  0.1UF 10V 10% X7S  pkg C0201  page 345 : 1 = P0V9_CPU1_RT_2D ; 2 = GND
C384  Q_CAP  1UF 4V 20% X6S  pkg 0201  page 345 : 1 = P0V9_CPU1_RT2_2A ; 2 = GND
C385  Q_CAP  0.1UF 10V 10% X7S  pkg C0201  page 345 : 1 = P0V9_CPU1_RT_2D ; 2 = GND
C386  Q_CAP  1UF 4V 20% X6S  pkg 0201  page 345 : 1 = P0V9_CPU1_RT2_2A ; 2 = GND
C387  Q_CAP  1UF 4V 20% X6S  pkg 0201  page 345 : 1 = P0V9_CPU1_RT2_2A ; 2 = GND
C388  Q_CAP  0.1UF 10V 10% X7S  pkg C0201  page 345 : 1 = P0V9_CPU1_RT_2D ; 2 = GND
C389  Q_CAP  1UF 4V 20% X6S  pkg 0201  page 345 : 1 = P0V9_CPU1_RT2_2A ; 2 = GND
C390  Q_CAP  1UF 4V 20% X6S  pkg 0201  page 345 : 1 = P0V9_CPU1_RT2_2A_2D ; 2 = GND
C391  Q_CAP  1UF 4V 20% X6S  pkg 0201  page 345 : 1 = P0V9_CPU1_RT2_2A ; 2 = GND
C392  Q_CAP  0.1UF 10V 10% X7S  pkg C0201  page 345 : 1 = P0V9_CPU1_RT_2D ; 2 = GND
C393  Q_CAP  0.1UF 10V 10% X7S  pkg C0201  page 345 : 1 = P0V9_CPU1_RT2_2A ; 2 = GND
C394  Q_CAP  1UF 4V 20% X6S  pkg 0201  page 345 : 1 = P0V9_CPU1_RT2_2A_2D ; 2 = GND
C395  Q_CAP  0.1UF 10V 10% X7S  pkg C0201  page 345 : 1 = P0V9_CPU1_RT2_2A ; 2 = GND
C396  Q_CAP  0.1UF 10V 10% X7S  pkg C0201  page 345 : 1 = P0V9_CPU1_RT2_2A_2D ; 2 = GND
C397  Q_CAP  0.1UF 10V 10% X7S  pkg C0201  page 345 : 1 = P0V9_CPU1_RT2_2A_2D ; 2 = GND
C398  Q_CAP  100UF 4V 20% X6S  pkg C0805  page 345 : 1 = P0V9_CPU1_RT2_2A ; 2 = GND
C399  Q_CAP  22UF 4V 20% X6S  pkg C0402  page 345 : 1 = P0V9_CPU1_RT2_2A ; 2 = GND
C400  Q_CAP  0.1UF 10V 10% X7S  pkg C0201  page 345 : 1 = P0V9_CPU1_RT2_2A ; 2 = GND
C401  Q_CAP  100UF 4V 20% X6S  pkg C0805  page 345 : 1 = P0V9_CPU1_RT2_2A ; 2 = GND
C402  Q_CAP  22UF 4V 20% X6S  pkg C0402  page 345 : 1 = P0V9_CPU1_RT2_2A ; 2 = GND
C403  Q_CAP  0.1UF 10V 10% X7S  pkg C0201  page 345 : 1 = P0V9_CPU1_RT2_2A ; 2 = GND
C404  Q_CAP  100UF 4V 20% X6S  pkg C0805  page 345 : 1 = P0V9_CPU1_RT_2D ; 2 = GND
C405  Q_CAP  100UF 4V 20% X6S  pkg C0805  page 345 : 1 = P0V9_CPU1_RT2_2A ; 2 = GND
C406  Q_CAP  4.7UF 6.3V 20% X6S  pkg 0402  page 345 : 1 = P0V9_CPU1_RT2_2A ; 2 = GND
C407  Q_CAP  1UF 4V 20% X6S  pkg 0201  page 345 : 1 = P0V9_CPU1_RT2_2A ; 2 = GND
C408  Q_CAP  22UF 4V 20% X6S  pkg C0402  page 345 : 1 = P0V9_CPU1_RT_2D ; 2 = GND
C409  Q_CAP  100UF 4V 20% X6S  pkg C0805  page 345 : 1 = P0V9_CPU1_RT2_2A ; 2 = GND
C410  Q_CAP  10UF 6.3V 20% X6S  pkg C0402  page 345 : 1 = P0V9_CPU1_RT2_2A ; 2 = GND
C411  Q_CAP  0.1UF 10V 10% X7S  pkg C0201  page 345 : 1 = P0V9_CPU1_RT2_2A ; 2 = GND
C412  Q_CAP  4.7UF 6.3V 20% X6S  pkg 0402  page 345 : 1 = P0V9_CPU1_RT2_2A ; 2 = GND
C413  Q_CAP  4.7UF 6.3V 20% X6S  pkg 0402  page 345 : 1 = P0V9_CPU1_RT2_2A ; 2 = GND
C414  Q_CAP  10UF 6.3V 20% X6S  pkg C0402  page 345 : 1 = P0V9_CPU1_RT_2D ; 2 = GND
C415  Q_CAP  1UF 4V 20% X6S  pkg 0201  page 345 : 1 = P0V9_CPU1_RT2_2A ; 2 = GND
C416  Q_CAP  4.7UF 6.3V 20% X6S  pkg 0402  page 345 : 1 = P0V9_CPU1_RT2_2A ; 2 = GND
C417  Q_CAP  22UF 4V 20% X6S  pkg C0402  page 345 : 1 = P0V9_CPU1_RT2_2A ; 2 = GND
C418  Q_CAP  1UF 4V 20% X6S  pkg 0201  page 345 : 1 = P0V9_CPU1_RT2_2A ; 2 = GND
C419  Q_CAP  4.7UF 6.3V 20% X6S  pkg 0402  page 345 : 1 = P0V9_CPU1_RT_2D ; 2 = GND
C420  Q_CAP  10UF 6.3V 20% X6S  pkg C0402  page 345 : 1 = P0V9_CPU1_RT2_2A ; 2 = GND
C421  Q_CAP  0.1UF 10V 10% X7S  pkg C0201  page 345 : 1 = P0V9_CPU1_RT2_2A ; 2 = GND
C422  Q_CAP  1UF 4V 20% X6S  pkg 0201  page 345 : 1 = P0V9_CPU1_RT2_2A ; 2 = GND
C423  Q_CAP  1UF 4V 20% X6S  pkg 0201  page 345 : 1 = P0V9_CPU1_RT_2D ; 2 = GND
C424  Q_CAP  22UF 4V 20% X6S  pkg C0402  page 345 : 1 = P0V9_CPU1_RT2_2A ; 2 = GND
C425  Q_CAP  1UF 4V 20% X6S  pkg 0201  page 345 : 1 = P0V9_CPU1_RT2_2A ; 2 = GND
C426  Q_CAP  0.1UF 10V 10% X7S  pkg C0201  page 345 : 1 = P0V9_CPU1_RT2_2A ; 2 = GND
C427  Q_CAP  0.1UF 10V 10% X7S  pkg C0201  page 345 : 1 = P0V9_CPU1_RT2_2A ; 2 = GND
C428  Q_CAP  0.1UF 10V 10% X7S  pkg C0201  page 345 : 1 = P0V9_CPU1_RT2_2A ; 2 = GND
C429  Q_CAP  10UF 6.3V 20% X6S  pkg C0402  page 345 : 1 = P0V9_CPU1_RT2_2A ; 2 = GND
C430  Q_CAP  0.1UF 10V 10% X7S  pkg C0201  page 345 : 1 = P0V9_CPU1_RT2_2A ; 2 = GND
C431  Q_CAP  10UF 6.3V 20% X6S  pkg C0402  page 345 : 1 = P0V9_CPU1_RT2_2A ; 2 = GND
C432  Q_CAP  100UF 4V 20% X6S  pkg C0805  page 356 : 1 = P1V8_CPU1_RT_1D ; 2 = GND
C433  Q_CAP  100UF 4V 20% X6S  pkg C0805  page 356 : 1 = P1V8_CPU1_RT3_1A ; 2 = GND
C434  Q_CAP  22UF 4V 20% X6S  pkg C0402  page 356 : 1 = P1V8_CPU1_RT_1D ; 2 = GND
C435  Q_CAP  22UF 4V 20% X6S  pkg C0402  page 356 : 1 = P1V8_CPU1_RT3_1A ; 2 = GND
C436  Q_CAP  10UF 6.3V 20% X6S  pkg C0402  page 356 : 1 = P1V8_CPU1_RT_1D ; 2 = GND
C437  Q_CAP  10UF 6.3V 20% X6S  pkg C0402  page 356 : 1 = P1V8_CPU1_RT3_1A ; 2 = GND
C438  Q_CAP  4.7UF 6.3V 20% X6S  pkg 0402  page 356 : 1 = P1V8_CPU1_RT3_1A ; 2 = GND
C439  Q_CAP  4.7UF 6.3V 20% X6S  pkg 0402  page 356 : 1 = P1V8_CPU1_RT_1D ; 2 = GND
C440  Q_CAP  1UF 4V 20% X6S  pkg 0201  page 356 : 1 = P1V8_CPU1_RT3_1A ; 2 = GND
C441  Q_CAP  1UF 4V 20% X6S  pkg 0201  page 356 : 1 = P1V8_CPU1_RT3_1A_1D ; 2 = GND
C442  Q_CAP  1UF 4V 20% X6S  pkg 0201  page 356 : 1 = P1V8_CPU1_RT3_1A ; 2 = GND
C443  Q_CAP  0.1UF 10V 10% X7S  pkg C0201  page 356 : 1 = P1V8_CPU1_RT3_1A ; 2 = GND
C444  Q_CAP  0.1UF 10V 10% X7S  pkg C0201  page 356 : 1 = P1V8_CPU1_RT3_1A_1D ; 2 = GND
C445  Q_CAP  0.1UF 10V 10% X7S  pkg C0201  page 356 : 1 = P1V8_CPU1_RT3_1A ; 2 = GND
C446  Q_CAP  0.1UF 10V 10% X7S  pkg C0201  page 356 : 1 = P1V8_CPU1_RT3_1A ; 2 = GND
C447  Q_CAP  0.1UF 10V 10% X7S  pkg C0201  page 356 : 1 = P1V8_CPU1_RT3_1A ; 2 = GND
C448  Q_CAP  1UF 4V 20% X6S  pkg 0201  page 356 : 1 = P0V9_CPU1_RT3_2A ; 2 = GND
C449  Q_CAP  0.1UF 10V 10% X7S  pkg C0201  page 356 : 1 = P0V9_CPU1_RT_2D ; 2 = GND
C450  Q_CAP  0.1UF 10V 10% X7S  pkg C0201  page 356 : 1 = P0V9_CPU1_RT3_2A ; 2 = GND
C451  Q_CAP  0.1UF 10V 10% X7S  pkg C0201  page 356 : 1 = P0V9_CPU1_RT_2D ; 2 = GND
C452  Q_CAP  1UF 4V 20% X6S  pkg 0201  page 356 : 1 = P0V9_CPU1_RT3_2A ; 2 = GND
C453  Q_CAP  1UF 4V 20% X6S  pkg 0201  page 356 : 1 = P0V9_CPU1_RT3_2A ; 2 = GND
C454  Q_CAP  1UF 4V 20% X6S  pkg 0201  page 356 : 1 = P0V9_CPU1_RT_2D ; 2 = GND
C455  Q_CAP  1UF 4V 20% X6S  pkg 0201  page 356 : 1 = P0V9_CPU1_RT3_2A ; 2 = GND
C456  Q_CAP  1UF 4V 20% X6S  pkg 0201  page 356 : 1 = P0V9_CPU1_RT3_2A_2D ; 2 = GND
C457  Q_CAP  0.1UF 10V 10% X7S  pkg C0201  page 356 : 1 = P0V9_CPU1_RT3_2A ; 2 = GND
C458  Q_CAP  0.1UF 10V 10% X7S  pkg C0201  page 356 : 1 = P0V9_CPU1_RT_2D ; 2 = GND
C459  Q_CAP  1UF 4V 20% X6S  pkg 0201  page 356 : 1 = P0V9_CPU1_RT3_2A ; 2 = GND
C460  Q_CAP  1UF 4V 20% X6S  pkg 0201  page 356 : 1 = P0V9_CPU1_RT3_2A_2D ; 2 = GND
C461  Q_CAP  1000PF 50V 5% X7R  pkg 0402  page 193 : 1 = PVDDCR_SOC_P0_EN_RC ; 2 = GND
C462  Q_CAP  0.1UF 10V 10% X7S  pkg C0201  page 356 : 1 = P0V9_CPU1_RT3_2A ; 2 = GND
C463  Q_CAP  0.1UF 10V 10% X7S  pkg C0201  page 356 : 1 = P0V9_CPU1_RT3_2A_2D ; 2 = GND
C464  Q_CAP  0.1UF 10V 10% X7S  pkg C0201  page 356 : 1 = P0V9_CPU1_RT3_2A_2D ; 2 = GND
C465  Q_CAP  1000PF 50V 5% EMPTY  pkg 0402  page 193 : 1 = PWRGD_PVDDCR_SOC_P0_R ; 2 = GND
C466  Q_CAP  100UF 4V 20% X6S  pkg C0805  page 356 : 1 = P0V9_CPU1_RT3_2A ; 2 = GND
C467  Q_CAP  1000PF 50V 5% EMPTY  pkg 0402  page 193 : 1 = PWRGD_PVDDCR_CPU0_P0_R ; 2 = GND
C468  Q_CAP  1000PF 50V 5% X7R  pkg 0402  page 193 : 1 = PVDDCR_CPU0_P0_EN_R ; 2 = GND
C469  Q_CAP  4.7UF 6.3V 20% X6S  pkg 0402  page 356 : 1 = P0V9_CPU1_RT3_2A ; 2 = GND
C470  Q_CAP  1UF 4V 20% X6S  pkg 0201  page 356 : 1 = P0V9_CPU1_RT3_2A ; 2 = GND
C471  Q_CAP  100UF 4V 20% X6S  pkg C0805  page 356 : 1 = P0V9_CPU1_RT3_2A ; 2 = GND
C472  Q_CAP  4.7UF 6.3V 20% X6S  pkg 0402  page 356 : 1 = P0V9_CPU1_RT3_2A ; 2 = GND
C473  Q_CAP  0.1UF 10V 10% X7S  pkg C0201  page 356 : 1 = P0V9_CPU1_RT3_2A ; 2 = GND
C474  Q_CAP  100UF 4V 20% X6S  pkg C0805  page 356 : 1 = P0V9_CPU1_RT_2D ; 2 = GND
C475  Q_CAP  100UF 4V 20% X6S  pkg C0805  page 356 : 1 = P0V9_CPU1_RT3_2A ; 2 = GND
C476  Q_CAP  22UF 4V 20% X6S  pkg C0402  page 356 : 1 = P0V9_CPU1_RT3_2A ; 2 = GND
C477  Q_CAP  0.1UF 10V 10% X7S  pkg C0201  page 356 : 1 = P0V9_CPU1_RT3_2A ; 2 = GND
C478  Q_CAP  22UF 4V 20% X6S  pkg C0402  page 356 : 1 = P0V9_CPU1_RT_2D ; 2 = GND
C479  Q_CAP  100UF 4V 20% X6S  pkg C0805  page 356 : 1 = P0V9_CPU1_RT3_2A ; 2 = GND
C480  Q_CAP  10UF 6.3V 20% X6S  pkg C0402  page 356 : 1 = P0V9_CPU1_RT3_2A ; 2 = GND
C481  Q_CAP  0.1UF 10V 10% X7S  pkg C0201  page 356 : 1 = P0V9_CPU1_RT3_2A ; 2 = GND
C482  Q_CAP  10UF 6.3V 20% X6S  pkg C0402  page 356 : 1 = P0V9_CPU1_RT3_2A ; 2 = GND
C483  Q_CAP  4.7UF 6.3V 20% X6S  pkg 0402  page 356 : 1 = P0V9_CPU1_RT3_2A ; 2 = GND
C484  Q_CAP  4.7UF 6.3V 20% X6S  pkg 0402  page 356 : 1 = P0V9_CPU1_RT_2D ; 2 = GND
C485  Q_CAP  1UF 4V 20% X6S  pkg 0201  page 356 : 1 = P0V9_CPU1_RT3_2A ; 2 = GND
C486  Q_CAP  22UF 4V 20% X6S  pkg C0402  page 356 : 1 = P0V9_CPU1_RT3_2A ; 2 = GND
C487  Q_CAP  22UF 4V 20% X6S  pkg C0402  page 356 : 1 = P0V9_CPU1_RT3_2A ; 2 = GND
C488  Q_CAP  1UF 4V 20% X6S  pkg 0201  page 356 : 1 = P0V9_CPU1_RT3_2A ; 2 = GND
C489  Q_CAP  10UF 6.3V 20% X6S  pkg C0402  page 356 : 1 = P0V9_CPU1_RT_2D ; 2 = GND
C490  Q_CAP  10UF 6.3V 20% X6S  pkg C0402  page 356 : 1 = P0V9_CPU1_RT3_2A ; 2 = GND
C491  Q_CAP  1UF 4V 20% X6S  pkg 0201  page 356 : 1 = P0V9_CPU1_RT3_2A ; 2 = GND
C492  Q_CAP  1UF 4V 20% X6S  pkg 0201  page 356 : 1 = P0V9_CPU1_RT3_2A ; 2 = GND
C493  Q_CAP  0.1UF 10V 10% X7S  pkg C0201  page 356 : 1 = P0V9_CPU1_RT_2D ; 2 = GND
C494  Q_CAP  4.7UF 6.3V 20% X6S  pkg 0402  page 356 : 1 = P0V9_CPU1_RT3_2A ; 2 = GND
C495  Q_CAP  0.1UF 10V 10% X7S  pkg C0201  page 356 : 1 = P0V9_CPU1_RT3_2A ; 2 = GND
C496  Q_CAP  0.1UF 10V 10% X7S  pkg C0201  page 356 : 1 = P0V9_CPU1_RT3_2A ; 2 = GND
C497  Q_CAP  1UF 4V 20% X6S  pkg 0201  page 356 : 1 = P0V9_CPU1_RT3_2A ; 2 = GND
C498  Q_CAP  0.1UF 10V 10% X7S  pkg C0201  page 356 : 1 = P0V9_CPU1_RT3_2A ; 2 = GND
C499  Q_CAP  10UF 6.3V 20% X6S  pkg C0402  page 356 : 1 = P0V9_CPU1_RT3_2A ; 2 = GND
C500  Q_CAP  0.1UF 10V 10% X7S  pkg C0201  page 356 : 1 = P0V9_CPU1_RT3_2A ; 2 = GND
C501  Q_CAP  22UF 4V 20% X6S  pkg C0402  page 356 : 1 = P0V9_CPU1_RT3_2A ; 2 = GND
C502  Q_CAP  100UF 4V 20% X6S  pkg C0805  page 279 : 1 = P1V8_CPU0_RT_1D ; 2 = GND
C503  Q_CAP  100UF 4V 20% X6S  pkg C0805  page 279 : 1 = P1V8_CPU0_RT0_1A ; 2 = GND
C504  Q_CAP  22UF 4V 20% X6S  pkg C0402  page 279 : 1 = P1V8_CPU0_RT_1D ; 2 = GND
C505  Q_CAP  22UF 4V 20% X6S  pkg C0402  page 279 : 1 = P1V8_CPU0_RT0_1A ; 2 = GND
C506  Q_CAP  10UF 6.3V 20% X6S  pkg C0402  page 279 : 1 = P1V8_CPU0_RT_1D ; 2 = GND
C507  Q_CAP  10UF 6.3V 20% X6S  pkg C0402  page 279 : 1 = P1V8_CPU0_RT0_1A ; 2 = GND
C508  Q_CAP  0.1UF 25V 10% X7R  pkg 0402  page 145 : 1 = P3V3_E1S_0 ; 2 = GND
C509  Q_CAP  10UF 25V 10% X6S  pkg C0805  page 102 : 1 = P12V_MEM_CPU1 ; 2 = GND
C510  Q_CAP  4.7UF 6.3V 20% X6S  pkg 0402  page 279 : 1 = P1V8_CPU0_RT0_1A ; 2 = GND
C511  Q_CAP  4.7UF 6.3V 20% X6S  pkg 0402  page 279 : 1 = P1V8_CPU0_RT_1D ; 2 = GND
C512  Q_CAP  1UF 4V 20% X6S  pkg 0201  page 279 : 1 = P1V8_CPU0_RT0_1A ; 2 = GND
C513  Q_CAP  1UF 4V 20% X6S  pkg 0201  page 279 : 1 = P1V8_CPU0_RT0_1A_1D ; 2 = GND
C514  Q_CAP  1UF 4V 20% X6S  pkg 0201  page 279 : 1 = P1V8_CPU0_RT0_1A ; 2 = GND
C515  Q_CAP  0.1UF 10V 10% X7S  pkg C0201  page 279 : 1 = P1V8_CPU0_RT0_1A ; 2 = GND
C516  Q_CAP  0.1UF 10V 10% X7S  pkg C0201  page 279 : 1 = P1V8_CPU0_RT0_1A_1D ; 2 = GND
C517  Q_CAP  0.1UF 10V 10% X7S  pkg C0201  page 279 : 1 = P1V8_CPU0_RT0_1A ; 2 = GND
